(kicad_pcb
	(version 20260206)
	(generator "pcbnew")
	(generator_version "10.0")
	(general
		(thickness 1.6)
		(legacy_teardrops no)
	)
	(paper "A4")
	(title_block
		(title "pdpb — Lightning_PDPB_BRD.brd")
		(comment 1 "Lightning (Wiwynn / Facebook NVMe JBOF) / footprints 1041-1047 of 1140")
	)
	(layers
		(0 "F.Cu" signal "TOP")
		(4 "In1.Cu" signal "L2GND")
		(6 "In2.Cu" signal "L3")
		(8 "In3.Cu" signal "L4VCC")
		(10 "In4.Cu" signal "L5VCC")
		(12 "In5.Cu" signal "L6")
		(14 "In6.Cu" signal "L7GND")
		(2 "B.Cu" signal "BOTTOM")
		(9 "F.Adhes" user "F.Adhesive")
		(11 "B.Adhes" user "B.Adhesive")
		(13 "F.Paste" user "Package Geometry/Pastemask Top")
		(15 "B.Paste" user "Package Geometry/Pastemask Bottom")
		(5 "F.SilkS" user "Ref Des/Silkscreen Top")
		(7 "B.SilkS" user "Ref Des/Silkscreen Bottom")
		(1 "F.Mask" user "Board Geometry/Soldermask Top")
		(3 "B.Mask" user "Board Geometry/Soldermask Bottom")
		(17 "Dwgs.User" user "User.Drawings")
		(19 "Cmts.User" user "User.Comments")
		(21 "Eco1.User" user "User.Eco1")
		(23 "Eco2.User" user "User.Eco2")
		(25 "Edge.Cuts" user "Board Geometry/Outline")
		(27 "Margin" user)
		(31 "F.CrtYd" user "Package Geometry/Place Bound Top")
		(29 "B.CrtYd" user "Package Geometry/Place Bound Bottom")
		(35 "F.Fab" user "Ref Des/Assembly Top")
		(33 "B.Fab" user "Ref Des/Assembly Bottom")
	)
	(footprint ""
		(layer "F.Cu")
		(at 91.186 -29.718 -90)
		(property "Reference" "C363"
			(at 0 0 270)
			(layer "F.SilkS")
			(hide yes)
			(effects
				(font
					(size 1.27 1.27)
				)
			)
		)
		(property "Value" "SC1U10V2KX-7-GP"
			(at 1.1811 -2.7051 270)
			(unlocked yes)
			(layer "F.Fab")
			(hide yes)
			(effects
				(font
					(size 1.016 1.016)
					(thickness 0.1524)
				)
			)
		)
		(property "Device Type" "C402H22"
			(at 1.1811 -4.2291 270)
			(unlocked yes)
			(layer "F.Fab")
			(hide yes)
			(effects
				(font
					(size 1.016 1.016)
					(thickness 0.1524)
				)
			)
		)
		(duplicate_pad_numbers_are_jumpers no)
		(fp_rect
			(start -0.4318 0.9525)
			(end 0.4318 -0.9525)
			(stroke
				(width 0)
				(type default)
			)
			(fill no)
			(layer "F.CrtYd")
		)
		(fp_rect
			(start -0.4318 0.9525)
			(end 0.4318 -0.9525)
			(stroke
				(width 0)
				(type default)
			)
			(fill no)
			(layer "F.Fab")
		)
		(pad "1" smd custom
			(at 0 -0.4445 270)
			(size 0.1524 0.1524)
			(layers "F.Cu" "F.Mask" "F.Paste")
			(net "P3V3")
			(options
				(clearance outline)
				(anchor circle)
			)
			(primitives
				(gr_poly
					(pts
						(arc
							(start 0.3048 -0.2032)
							(mid 0.275042 -0.275042)
							(end 0.2032 -0.3048)
						)
						(arc
							(start -0.2032 -0.3048)
							(mid -0.275042 -0.275042)
							(end -0.3048 -0.2032)
						)
						(arc
							(start -0.3048 0.2032)
							(mid -0.275042 0.275042)
							(end -0.2032 0.3048)
						)
						(arc
							(start 0.2032 0.3048)
							(mid 0.275042 0.275042)
							(end 0.3048 0.2032)
						)
					)
					(width 0)
					(fill yes)
				)
			)
		)
		(pad "2" smd custom
			(at 0 0.4445 270)
			(size 0.1524 0.1524)
			(layers "F.Cu" "F.Mask" "F.Paste")
			(net "GND")
			(options
				(clearance outline)
				(anchor circle)
			)
			(primitives
				(gr_poly
					(pts
						(arc
							(start 0.3048 -0.2032)
							(mid 0.275042 -0.275042)
							(end 0.2032 -0.3048)
						)
						(arc
							(start -0.2032 -0.3048)
							(mid -0.275042 -0.275042)
							(end -0.3048 -0.2032)
						)
						(arc
							(start -0.3048 0.2032)
							(mid -0.275042 0.275042)
							(end -0.2032 0.3048)
						)
						(arc
							(start 0.2032 0.3048)
							(mid 0.275042 0.275042)
							(end 0.3048 0.2032)
						)
					)
					(width 0)
					(fill yes)
				)
			)
		)
	)
	(footprint ""
		(layer "F.Cu")
		(at 77.343 -209.3722)
		(property "Reference" "R9971"
			(at 0 0 0)
			(layer "F.SilkS")
			(hide yes)
			(effects
				(font
					(size 1.27 1.27)
				)
			)
		)
		(property "Value" "56R2F-1-GP"
			(at 0.064008 -3.993896 0)
			(unlocked yes)
			(layer "F.Fab")
			(hide yes)
			(effects
				(font
					(size 1.016 1.016)
					(thickness 0.1524)
				)
			)
		)
		(property "Device Type" "R402H16"
			(at 0.064008 -5.517896 0)
			(unlocked yes)
			(layer "F.Fab")
			(hide yes)
			(effects
				(font
					(size 1.016 1.016)
					(thickness 0.1524)
				)
			)
		)
		(duplicate_pad_numbers_are_jumpers no)
		(fp_line
			(start -0.508 -0.9398)
			(end -0.508 0.9398)
			(stroke
				(width 0.1524)
				(type default)
			)
			(layer "F.SilkS")
		)
		(fp_line
			(start 0.508 -0.9398)
			(end -0.508 -0.9398)
			(stroke
				(width 0.1524)
				(type default)
			)
			(layer "F.SilkS")
		)
		(fp_rect
			(start -0.508 0.9398)
			(end 0.508 -0.9398)
			(stroke
				(width 0)
				(type default)
			)
			(fill no)
			(layer "F.CrtYd")
		)
		(fp_rect
			(start -0.508 0.9398)
			(end 0.508 -0.9398)
			(stroke
				(width 0)
				(type default)
			)
			(fill no)
			(layer "F.Fab")
		)
		(pad "1" smd custom
			(at 0 -0.4445)
			(size 0.1397 0.1397)
			(layers "F.Cu" "F.Mask" "F.Paste")
			(net "PE_100M_CLK2_N")
			(options
				(clearance outline)
				(anchor circle)
			)
			(primitives
				(gr_poly
					(pts
						(arc
							(start -0.1778 -0.2794)
							(mid -0.249642 -0.249642)
							(end -0.2794 -0.1778)
						)
						(arc
							(start -0.2794 0.1778)
							(mid -0.249642 0.249642)
							(end -0.1778 0.2794)
						)
						(arc
							(start 0.1778 0.2794)
							(mid 0.249642 0.249642)
							(end 0.2794 0.1778)
						)
						(arc
							(start 0.2794 -0.1778)
							(mid 0.249642 -0.249642)
							(end 0.1778 -0.2794)
						)
					)
					(width 0)
					(fill yes)
				)
			)
		)
		(pad "2" smd custom
			(at 0 0.4445)
			(size 0.1397 0.1397)
			(layers "F.Cu" "F.Mask" "F.Paste")
			(net "GND")
			(options
				(clearance outline)
				(anchor circle)
			)
			(primitives
				(gr_poly
					(pts
						(arc
							(start -0.1778 -0.2794)
							(mid -0.249642 -0.249642)
							(end -0.2794 -0.1778)
						)
						(arc
							(start -0.2794 0.1778)
							(mid -0.249642 0.249642)
							(end -0.1778 0.2794)
						)
						(arc
							(start 0.1778 0.2794)
							(mid 0.249642 0.249642)
							(end 0.2794 0.1778)
						)
						(arc
							(start 0.2794 -0.1778)
							(mid 0.249642 -0.249642)
							(end 0.1778 -0.2794)
						)
					)
					(width 0)
					(fill yes)
				)
			)
		)
	)
	(footprint ""
		(layer "F.Cu")
		(at 96.774 -116.586 90)
		(property "Reference" "R9505"
			(at 0 0 90)
			(layer "F.SilkS")
			(hide yes)
			(effects
				(font
					(size 1.27 1.27)
				)
			)
		)
		(property "Value" "4K7R2J-2-GP"
			(at 0.064008 -3.993896 90)
			(unlocked yes)
			(layer "F.Fab")
			(hide yes)
			(effects
				(font
					(size 1.016 1.016)
					(thickness 0.1524)
				)
			)
		)
		(property "Device Type" "R402H16"
			(at 0.064008 -5.517896 90)
			(unlocked yes)
			(layer "F.Fab")
			(hide yes)
			(effects
				(font
					(size 1.016 1.016)
					(thickness 0.1524)
				)
			)
		)
		(duplicate_pad_numbers_are_jumpers no)
		(fp_line
			(start 0.508 -0.9398)
			(end -0.508 -0.9398)
			(stroke
				(width 0.1524)
				(type default)
			)
			(layer "F.SilkS")
		)
		(fp_line
			(start -0.508 -0.9398)
			(end -0.508 0.9398)
			(stroke
				(width 0.1524)
				(type default)
			)
			(layer "F.SilkS")
		)
		(fp_rect
			(start -0.508 0.9398)
			(end 0.508 -0.9398)
			(stroke
				(width 0)
				(type default)
			)
			(fill no)
			(layer "F.CrtYd")
		)
		(fp_rect
			(start -0.508 0.9398)
			(end 0.508 -0.9398)
			(stroke
				(width 0)
				(type default)
			)
			(fill no)
			(layer "F.Fab")
		)
		(pad "1" smd custom
			(at 0 -0.4445 90)
			(size 0.1397 0.1397)
			(layers "F.Cu" "F.Mask" "F.Paste")
			(net "P3V3")
			(options
				(clearance outline)
				(anchor circle)
			)
			(primitives
				(gr_poly
					(pts
						(arc
							(start -0.1778 -0.2794)
							(mid -0.249642 -0.249642)
							(end -0.2794 -0.1778)
						)
						(arc
							(start -0.2794 0.1778)
							(mid -0.249642 0.249642)
							(end -0.1778 0.2794)
						)
						(arc
							(start 0.1778 0.2794)
							(mid 0.249642 0.249642)
							(end 0.2794 0.1778)
						)
						(arc
							(start 0.2794 -0.1778)
							(mid 0.249642 -0.249642)
							(end 0.1778 -0.2794)
						)
					)
					(width 0)
					(fill yes)
				)
			)
		)
		(pad "2" smd custom
			(at 0 0.4445 90)
			(size 0.1397 0.1397)
			(layers "F.Cu" "F.Mask" "F.Paste")
			(net "SSD8_CLK0_OE_N")
			(options
				(clearance outline)
				(anchor circle)
			)
			(primitives
				(gr_poly
					(pts
						(arc
							(start -0.1778 -0.2794)
							(mid -0.249642 -0.249642)
							(end -0.2794 -0.1778)
						)
						(arc
							(start -0.2794 0.1778)
							(mid -0.249642 0.249642)
							(end -0.1778 0.2794)
						)
						(arc
							(start 0.1778 0.2794)
							(mid 0.249642 0.249642)
							(end 0.2794 0.1778)
						)
						(arc
							(start 0.2794 -0.1778)
							(mid 0.249642 -0.249642)
							(end 0.1778 -0.2794)
						)
					)
					(width 0)
					(fill yes)
				)
			)
		)
	)
	(footprint ""
		(layer "F.Cu")
		(at 35.56 -308.0004 90)
		(property "Reference" "Q82"
			(at 0 0 90)
			(layer "F.SilkS")
			(hide yes)
			(effects
				(font
					(size 1.27 1.27)
				)
			)
		)
		(property "Value" "2N7002A-7-GP"
			(at 0.127 -8.9662 90)
			(unlocked yes)
			(layer "F.Fab")
			(hide yes)
			(effects
				(font
					(size 1.016 1.016)
					(thickness 0.1524)
				)
			)
		)
		(property "Device Type" "SOT23DGS2D4H48"
			(at 0.127 -10.4902 90)
			(unlocked yes)
			(layer "F.Fab")
			(hide yes)
			(effects
				(font
					(size 1.016 1.016)
					(thickness 0.1524)
				)
			)
		)
		(duplicate_pad_numbers_are_jumpers no)
		(fp_line
			(start 1.651 -1.778)
			(end -1.651 -1.778)
			(stroke
				(width 0.1524)
				(type default)
			)
			(layer "F.SilkS")
		)
		(fp_line
			(start -1.651 -1.778)
			(end -1.651 1.778)
			(stroke
				(width 0.1524)
				(type default)
			)
			(layer "F.SilkS")
		)
		(fp_line
			(start 1.651 1.778)
			(end 1.651 -1.778)
			(stroke
				(width 0.1524)
				(type default)
			)
			(layer "F.SilkS")
		)
		(fp_line
			(start -1.651 1.778)
			(end 1.651 1.778)
			(stroke
				(width 0.1524)
				(type default)
			)
			(layer "F.SilkS")
		)
		(fp_poly
			(pts
				(xy -1.778 1.8796) (xy -1.778 -1.8796) (xy 1.778 -1.8796) (xy 1.778 1.8796)
			)
			(stroke
				(width 0)
				(type default)
			)
			(fill no)
			(layer "F.CrtYd")
		)
		(fp_poly
			(pts
				(xy -1.778 1.8796) (xy -1.778 -1.8796) (xy 1.778 -1.8796) (xy 1.778 1.8796)
			)
			(stroke
				(width 0)
				(type default)
			)
			(fill no)
			(layer "F.Fab")
		)
		(pad "D" smd custom
			(at 0 -0.9525 90)
			(size 0.1905 0.1905)
			(layers "F.Cu" "F.Mask" "F.Paste")
			(net "P12V_MOST11_GATE")
			(options
				(clearance outline)
				(anchor circle)
			)
			(primitives
				(gr_poly
					(pts
						(arc
							(start -0.1778 0.5715)
							(mid -0.321484 0.511984)
							(end -0.381 0.3683)
						)
						(arc
							(start -0.381 -0.3683)
							(mid -0.321484 -0.511984)
							(end -0.1778 -0.5715)
						)
						(arc
							(start 0.1778 -0.5715)
							(mid 0.321484 -0.511984)
							(end 0.381 -0.3683)
						)
						(arc
							(start 0.381 0.3683)
							(mid 0.321484 0.511984)
							(end 0.1778 0.5715)
						)
					)
					(width 0)
					(fill yes)
				)
			)
		)
		(pad "G" smd custom
			(at -0.98425 0.9525 90)
			(size 0.1905 0.1905)
			(layers "F.Cu" "F.Mask" "F.Paste")
			(net "SSD11_PWREN_R")
			(options
				(clearance outline)
				(anchor circle)
			)
			(primitives
				(gr_poly
					(pts
						(arc
							(start -0.1778 0.5715)
							(mid -0.321484 0.511984)
							(end -0.381 0.3683)
						)
						(arc
							(start -0.381 -0.3683)
							(mid -0.321484 -0.511984)
							(end -0.1778 -0.5715)
						)
						(arc
							(start 0.1778 -0.5715)
							(mid 0.321484 -0.511984)
							(end 0.381 -0.3683)
						)
						(arc
							(start 0.381 0.3683)
							(mid 0.321484 0.511984)
							(end 0.1778 0.5715)
						)
					)
					(width 0)
					(fill yes)
				)
			)
		)
		(pad "S" smd custom
			(at 0.98425 0.9525 90)
			(size 0.1905 0.1905)
			(layers "F.Cu" "F.Mask" "F.Paste")
			(net "GND")
			(options
				(clearance outline)
				(anchor circle)
			)
			(primitives
				(gr_poly
					(pts
						(arc
							(start -0.1778 0.5715)
							(mid -0.321484 0.511984)
							(end -0.381 0.3683)
						)
						(arc
							(start -0.381 -0.3683)
							(mid -0.321484 -0.511984)
							(end -0.1778 -0.5715)
						)
						(arc
							(start 0.1778 -0.5715)
							(mid 0.321484 -0.511984)
							(end 0.381 -0.3683)
						)
						(arc
							(start 0.381 0.3683)
							(mid 0.321484 0.511984)
							(end 0.1778 0.5715)
						)
					)
					(width 0)
					(fill yes)
				)
			)
		)
	)
	(footprint ""
		(layer "F.Cu")
		(at 26.16835 -402.08835 180)
		(property "Reference" "R9820"
			(at 0 0 180)
			(layer "F.SilkS")
			(hide yes)
			(effects
				(font
					(size 1.27 1.27)
				)
			)
		)
		(property "Value" "47KR2J-2-GP"
			(at 0.064008 -3.993896 180)
			(unlocked yes)
			(layer "F.Fab")
			(hide yes)
			(effects
				(font
					(size 1.016 1.016)
					(thickness 0.1524)
				)
			)
		)
		(property "Device Type" "R402H16"
			(at 0.064008 -5.517896 180)
			(unlocked yes)
			(layer "F.Fab")
			(hide yes)
			(effects
				(font
					(size 1.016 1.016)
					(thickness 0.1524)
				)
			)
		)
		(duplicate_pad_numbers_are_jumpers no)
		(fp_line
			(start 0.508 -0.9398)
			(end -0.508 -0.9398)
			(stroke
				(width 0.1524)
				(type default)
			)
			(layer "F.SilkS")
		)
		(fp_line
			(start -0.508 -0.9398)
			(end -0.508 0.9398)
			(stroke
				(width 0.1524)
				(type default)
			)
			(layer "F.SilkS")
		)
		(fp_rect
			(start -0.508 0.9398)
			(end 0.508 -0.9398)
			(stroke
				(width 0)
				(type default)
			)
			(fill no)
			(layer "F.CrtYd")
		)
		(fp_rect
			(start -0.508 0.9398)
			(end 0.508 -0.9398)
			(stroke
				(width 0)
				(type default)
			)
			(fill no)
			(layer "F.Fab")
		)
		(pad "1" smd custom
			(at 0 -0.4445 180)
			(size 0.1397 0.1397)
			(layers "F.Cu" "F.Mask" "F.Paste")
			(net "P12V")
			(options
				(clearance outline)
				(anchor circle)
			)
			(primitives
				(gr_poly
					(pts
						(arc
							(start -0.1778 -0.2794)
							(mid -0.249642 -0.249642)
							(end -0.2794 -0.1778)
						)
						(arc
							(start -0.2794 0.1778)
							(mid -0.249642 0.249642)
							(end -0.1778 0.2794)
						)
						(arc
							(start 0.1778 0.2794)
							(mid 0.249642 0.249642)
							(end 0.2794 0.1778)
						)
						(arc
							(start 0.2794 -0.1778)
							(mid 0.249642 -0.249642)
							(end 0.1778 -0.2794)
						)
					)
					(width 0)
					(fill yes)
				)
			)
		)
		(pad "2" smd custom
			(at 0 0.4445 180)
			(size 0.1397 0.1397)
			(layers "F.Cu" "F.Mask" "F.Paste")
			(net "P12V_MOST6_GATE")
			(options
				(clearance outline)
				(anchor circle)
			)
			(primitives
				(gr_poly
					(pts
						(arc
							(start -0.1778 -0.2794)
							(mid -0.249642 -0.249642)
							(end -0.2794 -0.1778)
						)
						(arc
							(start -0.2794 0.1778)
							(mid -0.249642 0.249642)
							(end -0.1778 0.2794)
						)
						(arc
							(start 0.1778 0.2794)
							(mid 0.249642 0.249642)
							(end 0.2794 0.1778)
						)
						(arc
							(start 0.2794 -0.1778)
							(mid 0.249642 -0.249642)
							(end 0.1778 -0.2794)
						)
					)
					(width 0)
					(fill yes)
				)
			)
		)
	)
	(footprint ""
		(layer "F.Cu")
		(at 224.964752 -347.9038 90)
		(property "Reference" "R9913"
			(at 0 0 90)
			(layer "F.SilkS")
			(hide yes)
			(effects
				(font
					(size 1.27 1.27)
				)
			)
		)
		(property "Value" "47KR2J-2-GP"
			(at 0.064008 -3.993896 90)
			(unlocked yes)
			(layer "F.Fab")
			(hide yes)
			(effects
				(font
					(size 1.016 1.016)
					(thickness 0.1524)
				)
			)
		)
		(property "Device Type" "R402H16"
			(at 0.064008 -5.517896 90)
			(unlocked yes)
			(layer "F.Fab")
			(hide yes)
			(effects
				(font
					(size 1.016 1.016)
					(thickness 0.1524)
				)
			)
		)
		(duplicate_pad_numbers_are_jumpers no)
		(fp_line
			(start 0.508 -0.9398)
			(end -0.508 -0.9398)
			(stroke
				(width 0.1524)
				(type default)
			)
			(layer "F.SilkS")
		)
		(fp_line
			(start -0.508 -0.9398)
			(end -0.508 0.9398)
			(stroke
				(width 0.1524)
				(type default)
			)
			(layer "F.SilkS")
		)
		(fp_rect
			(start -0.508 0.9398)
			(end 0.508 -0.9398)
			(stroke
				(width 0)
				(type default)
			)
			(fill no)
			(layer "F.CrtYd")
		)
		(fp_rect
			(start -0.508 0.9398)
			(end 0.508 -0.9398)
			(stroke
				(width 0)
				(type default)
			)
			(fill no)
			(layer "F.Fab")
		)
		(pad "1" smd custom
			(at 0 -0.4445 90)
			(size 0.1397 0.1397)
			(layers "F.Cu" "F.Mask" "F.Paste")
			(net "P3V3")
			(options
				(clearance outline)
				(anchor circle)
			)
			(primitives
				(gr_poly
					(pts
						(arc
							(start -0.1778 -0.2794)
							(mid -0.249642 -0.249642)
							(end -0.2794 -0.1778)
						)
						(arc
							(start -0.2794 0.1778)
							(mid -0.249642 0.249642)
							(end -0.1778 0.2794)
						)
						(arc
							(start 0.1778 0.2794)
							(mid 0.249642 0.249642)
							(end 0.2794 0.1778)
						)
						(arc
							(start 0.2794 -0.1778)
							(mid 0.249642 -0.249642)
							(end 0.1778 -0.2794)
						)
					)
					(width 0)
					(fill yes)
				)
			)
		)
		(pad "2" smd custom
			(at 0 0.4445 90)
			(size 0.1397 0.1397)
			(layers "F.Cu" "F.Mask" "F.Paste")
			(net "ATTN_LED_DR1_N")
			(options
				(clearance outline)
				(anchor circle)
			)
			(primitives
				(gr_poly
					(pts
						(arc
							(start -0.1778 -0.2794)
							(mid -0.249642 -0.249642)
							(end -0.2794 -0.1778)
						)
						(arc
							(start -0.2794 0.1778)
							(mid -0.249642 0.249642)
							(end -0.1778 0.2794)
						)
						(arc
							(start 0.1778 0.2794)
							(mid 0.249642 0.249642)
							(end 0.2794 0.1778)
						)
						(arc
							(start 0.2794 -0.1778)
							(mid 0.249642 -0.249642)
							(end 0.1778 -0.2794)
						)
					)
					(width 0)
					(fill yes)
				)
			)
		)
	)
	(footprint ""
		(layer "F.Cu")
		(at 69.215 -435.864 180)
		(property "Reference" "PR9058"
			(at 0 0 180)
			(layer "F.SilkS")
			(hide yes)
			(effects
				(font
					(size 1.27 1.27)
				)
			)
		)
		(property "Value" "0R2J-2-GP"
			(at 0.064008 -3.993896 180)
			(unlocked yes)
			(layer "F.Fab")
			(hide yes)
			(effects
				(font
					(size 1.016 1.016)
					(thickness 0.1524)
				)
			)
		)
		(property "Device Type" "R402H16"
			(at 0.064008 -5.517896 180)
			(unlocked yes)
			(layer "F.Fab")
			(hide yes)
			(effects
				(font
					(size 1.016 1.016)
					(thickness 0.1524)
				)
			)
		)
		(duplicate_pad_numbers_are_jumpers no)
		(fp_line
			(start 0.508 -0.9398)
			(end -0.508 -0.9398)
			(stroke
				(width 0.1524)
				(type default)
			)
			(layer "F.SilkS")
		)
		(fp_line
			(start -0.508 -0.9398)
			(end -0.508 0.9398)
			(stroke
				(width 0.1524)
				(type default)
			)
			(layer "F.SilkS")
		)
		(fp_rect
			(start -0.508 0.9398)
			(end 0.508 -0.9398)
			(stroke
				(width 0)
				(type default)
			)
			(fill no)
			(layer "F.CrtYd")
		)
		(fp_rect
			(start -0.508 0.9398)
			(end 0.508 -0.9398)
			(stroke
				(width 0)
				(type default)
			)
			(fill no)
			(layer "F.Fab")
		)
		(pad "1" smd custom
			(at 0 -0.4445 180)
			(size 0.1397 0.1397)
			(layers "F.Cu" "F.Mask" "F.Paste")
			(net "SAS_I2C_B_BUF_SDA_R")
			(options
				(clearance outline)
				(anchor circle)
			)
			(primitives
				(gr_poly
					(pts
						(arc
							(start -0.1778 -0.2794)
							(mid -0.249642 -0.249642)
							(end -0.2794 -0.1778)
						)
						(arc
							(start -0.2794 0.1778)
							(mid -0.249642 0.249642)
							(end -0.1778 0.2794)
						)
						(arc
							(start 0.1778 0.2794)
							(mid 0.249642 0.249642)
							(end 0.2794 0.1778)
						)
						(arc
							(start 0.2794 -0.1778)
							(mid 0.249642 -0.249642)
							(end 0.1778 -0.2794)
						)
					)
					(width 0)
					(fill yes)
				)
			)
		)
		(pad "2" smd custom
			(at 0 0.4445 180)
			(size 0.1397 0.1397)
			(layers "F.Cu" "F.Mask" "F.Paste")
			(net "I2C_B_SDA")
			(options
				(clearance outline)
				(anchor circle)
			)
			(primitives
				(gr_poly
					(pts
						(arc
							(start -0.1778 -0.2794)
							(mid -0.249642 -0.249642)
							(end -0.2794 -0.1778)
						)
						(arc
							(start -0.2794 0.1778)
							(mid -0.249642 0.249642)
							(end -0.1778 0.2794)
						)
						(arc
							(start 0.1778 0.2794)
							(mid 0.249642 0.249642)
							(end 0.2794 0.1778)
						)
						(arc
							(start 0.2794 -0.1778)
							(mid 0.249642 -0.249642)
							(end 0.1778 -0.2794)
						)
					)
					(width 0)
					(fill yes)
				)
			)
		)
	)
)
